# TIMECARD (Time Appliance Project (Time Card)) — schematic netlist excerpt (pin names and nets, part order shuffled) for the footprints in the layout excerpt that follows; sources: Cadence DE-HDL packaged netlist, KiCad conversion of R4006-B0001-02_R01.brd

U2  G220_10198_01  pkg SOP8_154_P050_V1  page 9
  EN  = UNNAMED_3_G2201019801_I100_EN
  SCLOUT  = PCIE_SMCLK
  SCLIN  = PCIE_CONN_SMCLK
  GND  = SG
  READY  = NC
  SDAIN  = PCIE_CONN_SMDAT
  SDAOUT  = PCIE_SMDAT
  VCC  = XP3R3V_FPGA

(kicad_pcb
	(version 20260206)
	(generator "pcbnew")
	(generator_version "10.0")
	(general
		(thickness 1.6)
		(legacy_teardrops no)
	)
	(paper "A4")
	(title_block
		(title "timecard-production-celestica-r4006 — R4006-B0001-02_R01.brd")
		(comment 1 "Time Appliance Project (Time Card) / footprint 236 of 1113 (U2), pads 1-8 of 8")
	)
	(layers
		(0 "F.Cu" signal "TOP")
		(4 "In1.Cu" signal "L02_GND1")
		(6 "In2.Cu" signal "L03_SIG1")
		(8 "In3.Cu" signal "L04_GND2")
		(10 "In4.Cu" signal "L05_VCC1")
		(12 "In5.Cu" signal "L06_VCC2")
		(14 "In6.Cu" signal "L07_GND3")
		(16 "In7.Cu" signal "L08_SIG2")
		(18 "In8.Cu" signal "L09_GND4")
		(2 "B.Cu" signal "BOTTOM")
		(9 "F.Adhes" user "F.Adhesive")
		(11 "B.Adhes" user "B.Adhesive")
		(13 "F.Paste" user "Package Geometry/Pastemask Top")
		(15 "B.Paste" user "Package Geometry/Pastemask Bottom")
		(5 "F.SilkS" user "Ref Des/Silkscreen Top")
		(7 "B.SilkS" user "Ref Des/Silkscreen Bottom")
		(1 "F.Mask" user "Board Geometry/Soldermask Top")
		(3 "B.Mask" user "Board Geometry/Soldermask Bottom")
		(17 "Dwgs.User" user "User.Drawings")
		(19 "Cmts.User" user "User.Comments")
		(21 "Eco1.User" user "User.Eco1")
		(23 "Eco2.User" user "User.Eco2")
		(25 "Edge.Cuts" user "Board Geometry/Outline")
		(27 "Margin" user)
		(31 "F.CrtYd" user "Package Geometry/Place Bound Top")
		(29 "B.CrtYd" user "Package Geometry/Place Bound Bottom")
		(35 "F.Fab" user "Ref Des/Assembly Top")
		(33 "B.Fab" user "Ref Des/Assembly Bottom")
	)
	(footprint ""
		(layer "F.Cu")
		(at 45.02658 -16.891 180)
		(property "Reference" "U2"
			(at -0.66802 3.64363 0)
			(unlocked yes)
			(layer "F.SilkS")
			(effects
				(font
					(size 0.7874 0.5842)
					(thickness 0.1524)
				)
			)
		)
		(property "Value" ""
			(at 0 0 180)
			(layer "F.Fab")
			(effects
				(font
					(size 1.27 1.27)
				)
			)
		)
		(property "Device Type" "G220_10198_01-G223-10197-01"
			(at -0.0254 3.50647 180)
			(unlocked yes)
			(layer "F.Fab")
			(hide yes)
			(effects
				(font
					(size 0.7874 0.5842)
					(thickness 0.1524)
				)
			)
		)
		(property "User Part Number" "PARTNUM*"
			(at -0.0508 4.52247 180)
			(unlocked yes)
			(layer "Cmts.User")
			(hide yes)
			(effects
				(font
					(size 0.7874 0.5842)
					(thickness 0.1524)
				)
			)
		)
		(duplicate_pad_numbers_are_jumpers no)
		(pad "1" smd rect
			(at -2.8067 -1.905 270)
			(size 0.508 1.651)
			(layers "F.Cu" "F.Mask" "F.Paste")
			(net "UNNAMED_3_G2201019801_I100_EN")
		)
		(pad "2" smd rect
			(at -2.8067 -0.635 270)
			(size 0.508 1.651)
			(layers "F.Cu" "F.Mask" "F.Paste")
			(net "PCIE_SMCLK")
		)
		(pad "3" smd rect
			(at -2.8067 0.635 270)
			(size 0.508 1.651)
			(layers "F.Cu" "F.Mask" "F.Paste")
			(net "PCIE_CONN_SMCLK")
		)
		(pad "4" smd rect
			(at -2.8067 1.905 270)
			(size 0.508 1.651)
			(layers "F.Cu" "F.Mask" "F.Paste")
			(net "SG")
		)
		(pad "5" smd rect
			(at 2.8067 1.905 270)
			(size 0.508 1.651)
			(layers "F.Cu" "F.Mask" "F.Paste")
			(net "Net_628")
		)
		(pad "6" smd rect
			(at 2.8067 0.635 270)
			(size 0.508 1.651)
			(layers "F.Cu" "F.Mask" "F.Paste")
			(net "PCIE_CONN_SMDAT")
		)
		(pad "7" smd rect
			(at 2.8067 -0.635 270)
			(size 0.508 1.651)
			(layers "F.Cu" "F.Mask" "F.Paste")
			(net "PCIE_SMDAT")
		)
		(pad "8" smd rect
			(at 2.8067 -1.905 270)
			(size 0.508 1.651)
			(layers "F.Cu" "F.Mask" "F.Paste")
			(net "XP3R3V_FPGA")
		)
	)
)
